(kicad_pcb
	(version 20260206)
	(generator "pcbnew")
	(generator_version "10.0")
	(general
		(thickness 1.6)
		(legacy_teardrops no)
	)
	(paper "A4")
	(title_block
		(title "pdpb — Lightning_PDPB_BRD.brd")
		(comment 1 "Lightning (Wiwynn / Facebook NVMe JBOF) / footprints 1034-1040 of 1140")
	)
	(layers
		(0 "F.Cu" signal "TOP")
		(4 "In1.Cu" signal "L2GND")
		(6 "In2.Cu" signal "L3")
		(8 "In3.Cu" signal "L4VCC")
		(10 "In4.Cu" signal "L5VCC")
		(12 "In5.Cu" signal "L6")
		(14 "In6.Cu" signal "L7GND")
		(2 "B.Cu" signal "BOTTOM")
		(9 "F.Adhes" user "F.Adhesive")
		(11 "B.Adhes" user "B.Adhesive")
		(13 "F.Paste" user "Package Geometry/Pastemask Top")
		(15 "B.Paste" user "Package Geometry/Pastemask Bottom")
		(5 "F.SilkS" user "Ref Des/Silkscreen Top")
		(7 "B.SilkS" user "Ref Des/Silkscreen Bottom")
		(1 "F.Mask" user "Board Geometry/Soldermask Top")
		(3 "B.Mask" user "Board Geometry/Soldermask Bottom")
		(17 "Dwgs.User" user "User.Drawings")
		(19 "Cmts.User" user "User.Comments")
		(21 "Eco1.User" user "User.Eco1")
		(23 "Eco2.User" user "User.Eco2")
		(25 "Edge.Cuts" user "Board Geometry/Outline")
		(27 "Margin" user)
		(31 "F.CrtYd" user "Package Geometry/Place Bound Top")
		(29 "B.CrtYd" user "Package Geometry/Place Bound Bottom")
		(35 "F.Fab" user "Ref Des/Assembly Top")
		(33 "B.Fab" user "Ref Des/Assembly Bottom")
	)
	(footprint ""
		(layer "F.Cu")
		(at 106.045 -205.994 180)
		(property "Reference" "C9351"
			(at 0 0 180)
			(layer "F.SilkS")
			(hide yes)
			(effects
				(font
					(size 1.27 1.27)
				)
			)
		)
		(property "Value" "SC1KP50V2KX-1GP"
			(at 1.1811 -2.7051 180)
			(unlocked yes)
			(layer "F.Fab")
			(hide yes)
			(effects
				(font
					(size 1.016 1.016)
					(thickness 0.1524)
				)
			)
		)
		(property "Device Type" "C402H22"
			(at 1.1811 -4.2291 180)
			(unlocked yes)
			(layer "F.Fab")
			(hide yes)
			(effects
				(font
					(size 1.016 1.016)
					(thickness 0.1524)
				)
			)
		)
		(duplicate_pad_numbers_are_jumpers no)
		(fp_rect
			(start -0.4318 0.9525)
			(end 0.4318 -0.9525)
			(stroke
				(width 0)
				(type default)
			)
			(fill no)
			(layer "F.CrtYd")
		)
		(fp_rect
			(start -0.4318 0.9525)
			(end 0.4318 -0.9525)
			(stroke
				(width 0)
				(type default)
			)
			(fill no)
			(layer "F.Fab")
		)
		(pad "1" smd custom
			(at 0 -0.4445 180)
			(size 0.1524 0.1524)
			(layers "F.Cu" "F.Mask" "F.Paste")
			(net "SSD_PRSNT3")
			(options
				(clearance outline)
				(anchor circle)
			)
			(primitives
				(gr_poly
					(pts
						(arc
							(start 0.3048 -0.2032)
							(mid 0.275042 -0.275042)
							(end 0.2032 -0.3048)
						)
						(arc
							(start -0.2032 -0.3048)
							(mid -0.275042 -0.275042)
							(end -0.3048 -0.2032)
						)
						(arc
							(start -0.3048 0.2032)
							(mid -0.275042 0.275042)
							(end -0.2032 0.3048)
						)
						(arc
							(start 0.2032 0.3048)
							(mid 0.275042 0.275042)
							(end 0.3048 0.2032)
						)
					)
					(width 0)
					(fill yes)
				)
			)
		)
		(pad "2" smd custom
			(at 0 0.4445 180)
			(size 0.1524 0.1524)
			(layers "F.Cu" "F.Mask" "F.Paste")
			(net "GND")
			(options
				(clearance outline)
				(anchor circle)
			)
			(primitives
				(gr_poly
					(pts
						(arc
							(start 0.3048 -0.2032)
							(mid 0.275042 -0.275042)
							(end 0.2032 -0.3048)
						)
						(arc
							(start -0.2032 -0.3048)
							(mid -0.275042 -0.275042)
							(end -0.3048 -0.2032)
						)
						(arc
							(start -0.3048 0.2032)
							(mid -0.275042 0.275042)
							(end -0.2032 0.3048)
						)
						(arc
							(start 0.2032 0.3048)
							(mid 0.275042 0.275042)
							(end 0.3048 0.2032)
						)
					)
					(width 0)
					(fill yes)
				)
			)
		)
	)
	(footprint ""
		(layer "F.Cu")
		(at 232.029 -431.546 -90)
		(property "Reference" "PC1288"
			(at 0 0 270)
			(layer "F.SilkS")
			(hide yes)
			(effects
				(font
					(size 1.27 1.27)
				)
			)
		)
		(property "Value" "SC1U10V2KX-7-GP"
			(at 1.1811 -2.7051 270)
			(unlocked yes)
			(layer "F.Fab")
			(hide yes)
			(effects
				(font
					(size 1.016 1.016)
					(thickness 0.1524)
				)
			)
		)
		(property "Device Type" "C402H22"
			(at 1.1811 -4.2291 270)
			(unlocked yes)
			(layer "F.Fab")
			(hide yes)
			(effects
				(font
					(size 1.016 1.016)
					(thickness 0.1524)
				)
			)
		)
		(duplicate_pad_numbers_are_jumpers no)
		(fp_rect
			(start -0.4318 0.9525)
			(end 0.4318 -0.9525)
			(stroke
				(width 0)
				(type default)
			)
			(fill no)
			(layer "F.CrtYd")
		)
		(fp_rect
			(start -0.4318 0.9525)
			(end 0.4318 -0.9525)
			(stroke
				(width 0)
				(type default)
			)
			(fill no)
			(layer "F.Fab")
		)
		(pad "1" smd custom
			(at 0 -0.4445 270)
			(size 0.1524 0.1524)
			(layers "F.Cu" "F.Mask" "F.Paste")
			(net "P3V3_CC_R")
			(options
				(clearance outline)
				(anchor circle)
			)
			(primitives
				(gr_poly
					(pts
						(arc
							(start 0.3048 -0.2032)
							(mid 0.275042 -0.275042)
							(end 0.2032 -0.3048)
						)
						(arc
							(start -0.2032 -0.3048)
							(mid -0.275042 -0.275042)
							(end -0.3048 -0.2032)
						)
						(arc
							(start -0.3048 0.2032)
							(mid -0.275042 0.275042)
							(end -0.2032 0.3048)
						)
						(arc
							(start 0.2032 0.3048)
							(mid 0.275042 0.275042)
							(end 0.3048 0.2032)
						)
					)
					(width 0)
					(fill yes)
				)
			)
		)
		(pad "2" smd custom
			(at 0 0.4445 270)
			(size 0.1524 0.1524)
			(layers "F.Cu" "F.Mask" "F.Paste")
			(net "P3V3_VFB")
			(options
				(clearance outline)
				(anchor circle)
			)
			(primitives
				(gr_poly
					(pts
						(arc
							(start 0.3048 -0.2032)
							(mid 0.275042 -0.275042)
							(end 0.2032 -0.3048)
						)
						(arc
							(start -0.2032 -0.3048)
							(mid -0.275042 -0.275042)
							(end -0.3048 -0.2032)
						)
						(arc
							(start -0.3048 0.2032)
							(mid -0.275042 0.275042)
							(end -0.2032 0.3048)
						)
						(arc
							(start 0.2032 0.3048)
							(mid 0.275042 0.275042)
							(end 0.3048 0.2032)
						)
					)
					(width 0)
					(fill yes)
				)
			)
		)
	)
	(footprint ""
		(layer "F.Cu")
		(at 16.160242 -155.66898 180)
		(property "Reference" "R9954"
			(at 0 0 180)
			(layer "F.SilkS")
			(hide yes)
			(effects
				(font
					(size 1.27 1.27)
				)
			)
		)
		(property "Value" "4K7R2J-2-GP"
			(at 0.064008 -3.993896 180)
			(unlocked yes)
			(layer "F.Fab")
			(hide yes)
			(effects
				(font
					(size 1.016 1.016)
					(thickness 0.1524)
				)
			)
		)
		(property "Device Type" "R402H16"
			(at 0.064008 -5.517896 180)
			(unlocked yes)
			(layer "F.Fab")
			(hide yes)
			(effects
				(font
					(size 1.016 1.016)
					(thickness 0.1524)
				)
			)
		)
		(duplicate_pad_numbers_are_jumpers no)
		(fp_line
			(start 0.508 -0.9398)
			(end -0.508 -0.9398)
			(stroke
				(width 0.1524)
				(type default)
			)
			(layer "F.SilkS")
		)
		(fp_line
			(start -0.508 -0.9398)
			(end -0.508 0.9398)
			(stroke
				(width 0.1524)
				(type default)
			)
			(layer "F.SilkS")
		)
		(fp_rect
			(start -0.508 0.9398)
			(end 0.508 -0.9398)
			(stroke
				(width 0)
				(type default)
			)
			(fill no)
			(layer "F.CrtYd")
		)
		(fp_rect
			(start -0.508 0.9398)
			(end 0.508 -0.9398)
			(stroke
				(width 0)
				(type default)
			)
			(fill no)
			(layer "F.Fab")
		)
		(pad "1" smd custom
			(at 0 -0.4445 180)
			(size 0.1397 0.1397)
			(layers "F.Cu" "F.Mask" "F.Paste")
			(net "P3V3")
			(options
				(clearance outline)
				(anchor circle)
			)
			(primitives
				(gr_poly
					(pts
						(arc
							(start -0.1778 -0.2794)
							(mid -0.249642 -0.249642)
							(end -0.2794 -0.1778)
						)
						(arc
							(start -0.2794 0.1778)
							(mid -0.249642 0.249642)
							(end -0.1778 0.2794)
						)
						(arc
							(start 0.1778 0.2794)
							(mid 0.249642 0.249642)
							(end 0.2794 0.1778)
						)
						(arc
							(start 0.2794 -0.1778)
							(mid 0.249642 -0.249642)
							(end 0.1778 -0.2794)
						)
					)
					(width 0)
					(fill yes)
				)
			)
		)
		(pad "2" smd custom
			(at 0 0.4445 180)
			(size 0.1397 0.1397)
			(layers "F.Cu" "F.Mask" "F.Paste")
			(net "SSD_ACT_DR13_MOS_N")
			(options
				(clearance outline)
				(anchor circle)
			)
			(primitives
				(gr_poly
					(pts
						(arc
							(start -0.1778 -0.2794)
							(mid -0.249642 -0.249642)
							(end -0.2794 -0.1778)
						)
						(arc
							(start -0.2794 0.1778)
							(mid -0.249642 0.249642)
							(end -0.1778 0.2794)
						)
						(arc
							(start 0.1778 0.2794)
							(mid 0.249642 0.249642)
							(end 0.2794 0.1778)
						)
						(arc
							(start 0.2794 -0.1778)
							(mid 0.249642 -0.249642)
							(end 0.1778 -0.2794)
						)
					)
					(width 0)
					(fill yes)
				)
			)
		)
	)
	(footprint ""
		(layer "F.Cu")
		(at 210.947 -403.9616 -90)
		(property "Reference" "Q31"
			(at 0 0 270)
			(layer "F.SilkS")
			(hide yes)
			(effects
				(font
					(size 1.27 1.27)
				)
			)
		)
		(property "Value" "2N7002A-7-GP"
			(at 0.127 -8.9662 270)
			(unlocked yes)
			(layer "F.Fab")
			(hide yes)
			(effects
				(font
					(size 1.016 1.016)
					(thickness 0.1524)
				)
			)
		)
		(property "Device Type" "SOT23DGS2D4H48"
			(at 0.127 -10.4902 270)
			(unlocked yes)
			(layer "F.Fab")
			(hide yes)
			(effects
				(font
					(size 1.016 1.016)
					(thickness 0.1524)
				)
			)
		)
		(duplicate_pad_numbers_are_jumpers no)
		(fp_line
			(start -1.651 1.778)
			(end 1.651 1.778)
			(stroke
				(width 0.1524)
				(type default)
			)
			(layer "F.SilkS")
		)
		(fp_line
			(start 1.651 1.778)
			(end 1.651 -1.778)
			(stroke
				(width 0.1524)
				(type default)
			)
			(layer "F.SilkS")
		)
		(fp_line
			(start -1.651 -1.778)
			(end -1.651 1.778)
			(stroke
				(width 0.1524)
				(type default)
			)
			(layer "F.SilkS")
		)
		(fp_line
			(start 1.651 -1.778)
			(end -1.651 -1.778)
			(stroke
				(width 0.1524)
				(type default)
			)
			(layer "F.SilkS")
		)
		(fp_poly
			(pts
				(xy -1.778 1.8796) (xy -1.778 -1.8796) (xy 1.778 -1.8796) (xy 1.778 1.8796)
			)
			(stroke
				(width 0)
				(type default)
			)
			(fill no)
			(layer "F.CrtYd")
		)
		(fp_poly
			(pts
				(xy -1.778 1.8796) (xy -1.778 -1.8796) (xy 1.778 -1.8796) (xy 1.778 1.8796)
			)
			(stroke
				(width 0)
				(type default)
			)
			(fill no)
			(layer "F.Fab")
		)
		(pad "D" smd custom
			(at 0 -0.9525 270)
			(size 0.1905 0.1905)
			(layers "F.Cu" "F.Mask" "F.Paste")
			(net "P12V_MOST1_GATE")
			(options
				(clearance outline)
				(anchor circle)
			)
			(primitives
				(gr_poly
					(pts
						(arc
							(start -0.1778 0.5715)
							(mid -0.321484 0.511984)
							(end -0.381 0.3683)
						)
						(arc
							(start -0.381 -0.3683)
							(mid -0.321484 -0.511984)
							(end -0.1778 -0.5715)
						)
						(arc
							(start 0.1778 -0.5715)
							(mid 0.321484 -0.511984)
							(end 0.381 -0.3683)
						)
						(arc
							(start 0.381 0.3683)
							(mid 0.321484 0.511984)
							(end 0.1778 0.5715)
						)
					)
					(width 0)
					(fill yes)
				)
			)
		)
		(pad "G" smd custom
			(at -0.98425 0.9525 270)
			(size 0.1905 0.1905)
			(layers "F.Cu" "F.Mask" "F.Paste")
			(net "SSD1_PWREN_R")
			(options
				(clearance outline)
				(anchor circle)
			)
			(primitives
				(gr_poly
					(pts
						(arc
							(start -0.1778 0.5715)
							(mid -0.321484 0.511984)
							(end -0.381 0.3683)
						)
						(arc
							(start -0.381 -0.3683)
							(mid -0.321484 -0.511984)
							(end -0.1778 -0.5715)
						)
						(arc
							(start 0.1778 -0.5715)
							(mid 0.321484 -0.511984)
							(end 0.381 -0.3683)
						)
						(arc
							(start 0.381 0.3683)
							(mid 0.321484 0.511984)
							(end 0.1778 0.5715)
						)
					)
					(width 0)
					(fill yes)
				)
			)
		)
		(pad "S" smd custom
			(at 0.98425 0.9525 270)
			(size 0.1905 0.1905)
			(layers "F.Cu" "F.Mask" "F.Paste")
			(net "GND")
			(options
				(clearance outline)
				(anchor circle)
			)
			(primitives
				(gr_poly
					(pts
						(arc
							(start -0.1778 0.5715)
							(mid -0.321484 0.511984)
							(end -0.381 0.3683)
						)
						(arc
							(start -0.381 -0.3683)
							(mid -0.321484 -0.511984)
							(end -0.1778 -0.5715)
						)
						(arc
							(start 0.1778 -0.5715)
							(mid 0.321484 -0.511984)
							(end 0.381 -0.3683)
						)
						(arc
							(start 0.381 0.3683)
							(mid 0.321484 0.511984)
							(end 0.1778 0.5715)
						)
					)
					(width 0)
					(fill yes)
				)
			)
		)
	)
	(footprint ""
		(layer "F.Cu")
		(at 20.066 -270.379952 -90)
		(property "Reference" "R9861"
			(at 0 0 270)
			(layer "F.SilkS")
			(hide yes)
			(effects
				(font
					(size 1.27 1.27)
				)
			)
		)
		(property "Value" "0R2J-2-GP"
			(at 0.064008 -3.993896 270)
			(unlocked yes)
			(layer "F.Fab")
			(hide yes)
			(effects
				(font
					(size 1.016 1.016)
					(thickness 0.1524)
				)
			)
		)
		(property "Device Type" "R402H16"
			(at 0.064008 -5.517896 270)
			(unlocked yes)
			(layer "F.Fab")
			(hide yes)
			(effects
				(font
					(size 1.016 1.016)
					(thickness 0.1524)
				)
			)
		)
		(duplicate_pad_numbers_are_jumpers no)
		(fp_line
			(start -0.508 -0.9398)
			(end -0.508 0.9398)
			(stroke
				(width 0.1524)
				(type default)
			)
			(layer "F.SilkS")
		)
		(fp_line
			(start 0.508 -0.9398)
			(end -0.508 -0.9398)
			(stroke
				(width 0.1524)
				(type default)
			)
			(layer "F.SilkS")
		)
		(fp_rect
			(start -0.508 0.9398)
			(end 0.508 -0.9398)
			(stroke
				(width 0)
				(type default)
			)
			(fill no)
			(layer "F.CrtYd")
		)
		(fp_rect
			(start -0.508 0.9398)
			(end 0.508 -0.9398)
			(stroke
				(width 0)
				(type default)
			)
			(fill no)
			(layer "F.Fab")
		)
		(pad "1" smd custom
			(at 0 -0.4445 270)
			(size 0.1397 0.1397)
			(layers "F.Cu" "F.Mask" "F.Paste")
			(net "ATTN_LED_DR12_AND")
			(options
				(clearance outline)
				(anchor circle)
			)
			(primitives
				(gr_poly
					(pts
						(arc
							(start -0.1778 -0.2794)
							(mid -0.249642 -0.249642)
							(end -0.2794 -0.1778)
						)
						(arc
							(start -0.2794 0.1778)
							(mid -0.249642 0.249642)
							(end -0.1778 0.2794)
						)
						(arc
							(start 0.1778 0.2794)
							(mid 0.249642 0.249642)
							(end 0.2794 0.1778)
						)
						(arc
							(start 0.2794 -0.1778)
							(mid 0.249642 -0.249642)
							(end 0.1778 -0.2794)
						)
					)
					(width 0)
					(fill yes)
				)
			)
		)
		(pad "2" smd custom
			(at 0 0.4445 270)
			(size 0.1397 0.1397)
			(layers "F.Cu" "F.Mask" "F.Paste")
			(net "ATTN_LED_DR12_AND_R")
			(options
				(clearance outline)
				(anchor circle)
			)
			(primitives
				(gr_poly
					(pts
						(arc
							(start -0.1778 -0.2794)
							(mid -0.249642 -0.249642)
							(end -0.2794 -0.1778)
						)
						(arc
							(start -0.2794 0.1778)
							(mid -0.249642 0.249642)
							(end -0.1778 0.2794)
						)
						(arc
							(start 0.1778 0.2794)
							(mid 0.249642 0.249642)
							(end 0.2794 0.1778)
						)
						(arc
							(start 0.2794 -0.1778)
							(mid 0.249642 -0.249642)
							(end 0.1778 -0.2794)
						)
					)
					(width 0)
					(fill yes)
				)
			)
		)
	)
	(footprint ""
		(layer "F.Cu")
		(at 90.043 -419.735 90)
		(property "Reference" "C132"
			(at 0 0 90)
			(layer "F.SilkS")
			(hide yes)
			(effects
				(font
					(size 1.27 1.27)
				)
			)
		)
		(property "Value" "SC1KP50V2KX-1GP"
			(at 1.1811 -2.7051 90)
			(unlocked yes)
			(layer "F.Fab")
			(hide yes)
			(effects
				(font
					(size 1.016 1.016)
					(thickness 0.1524)
				)
			)
		)
		(property "Device Type" "C402H22"
			(at 1.1811 -4.2291 90)
			(unlocked yes)
			(layer "F.Fab")
			(hide yes)
			(effects
				(font
					(size 1.016 1.016)
					(thickness 0.1524)
				)
			)
		)
		(duplicate_pad_numbers_are_jumpers no)
		(fp_rect
			(start -0.4318 0.9525)
			(end 0.4318 -0.9525)
			(stroke
				(width 0)
				(type default)
			)
			(fill no)
			(layer "F.CrtYd")
		)
		(fp_rect
			(start -0.4318 0.9525)
			(end 0.4318 -0.9525)
			(stroke
				(width 0)
				(type default)
			)
			(fill no)
			(layer "F.Fab")
		)
		(pad "1" smd custom
			(at 0 -0.4445 90)
			(size 0.1524 0.1524)
			(layers "F.Cu" "F.Mask" "F.Paste")
			(net "SSD10_CLK0_OE_R_N")
			(options
				(clearance outline)
				(anchor circle)
			)
			(primitives
				(gr_poly
					(pts
						(arc
							(start 0.3048 -0.2032)
							(mid 0.275042 -0.275042)
							(end 0.2032 -0.3048)
						)
						(arc
							(start -0.2032 -0.3048)
							(mid -0.275042 -0.275042)
							(end -0.3048 -0.2032)
						)
						(arc
							(start -0.3048 0.2032)
							(mid -0.275042 0.275042)
							(end -0.2032 0.3048)
						)
						(arc
							(start 0.2032 0.3048)
							(mid 0.275042 0.275042)
							(end 0.3048 0.2032)
						)
					)
					(width 0)
					(fill yes)
				)
			)
		)
		(pad "2" smd custom
			(at 0 0.4445 90)
			(size 0.1524 0.1524)
			(layers "F.Cu" "F.Mask" "F.Paste")
			(net "GND")
			(options
				(clearance outline)
				(anchor circle)
			)
			(primitives
				(gr_poly
					(pts
						(arc
							(start 0.3048 -0.2032)
							(mid 0.275042 -0.275042)
							(end 0.2032 -0.3048)
						)
						(arc
							(start -0.2032 -0.3048)
							(mid -0.275042 -0.275042)
							(end -0.3048 -0.2032)
						)
						(arc
							(start -0.3048 0.2032)
							(mid -0.275042 0.275042)
							(end -0.2032 0.3048)
						)
						(arc
							(start 0.2032 0.3048)
							(mid 0.275042 0.275042)
							(end 0.3048 0.2032)
						)
					)
					(width 0)
					(fill yes)
				)
			)
		)
	)
	(footprint ""
		(layer "F.Cu")
		(at 82.0674 -148.1836 90)
		(property "Reference" "C9322"
			(at 0 0 90)
			(layer "F.SilkS")
			(hide yes)
			(effects
				(font
					(size 1.27 1.27)
				)
			)
		)
		(property "Value" "SCD1U25V3KX-GP"
			(at 0 -2.8194 90)
			(unlocked yes)
			(layer "F.Fab")
			(hide yes)
			(effects
				(font
					(size 1.016 1.016)
					(thickness 0.1524)
				)
			)
		)
		(property "Device Type" "C603H36"
			(at 0 -4.3434 90)
			(unlocked yes)
			(layer "F.Fab")
			(hide yes)
			(effects
				(font
					(size 1.016 1.016)
					(thickness 0.1524)
				)
			)
		)
		(duplicate_pad_numbers_are_jumpers no)
		(fp_line
			(start 0.508 0)
			(end -0.508 0)
			(stroke
				(width 0.2032)
				(type default)
			)
			(layer "F.SilkS")
		)
		(fp_rect
			(start -0.5842 1.3335)
			(end 0.5842 -1.3335)
			(stroke
				(width 0)
				(type default)
			)
			(fill no)
			(layer "F.CrtYd")
		)
		(fp_rect
			(start -0.5842 1.3335)
			(end 0.5842 -1.3335)
			(stroke
				(width 0)
				(type default)
			)
			(fill no)
			(layer "F.Fab")
		)
		(pad "1" smd custom
			(at 0 -0.762 90)
			(size 0.2159 0.2159)
			(layers "F.Cu" "F.Mask" "F.Paste")
			(net "P3V3")
			(options
				(clearance outline)
				(anchor circle)
			)
			(primitives
				(gr_poly
					(pts
						(arc
							(start -0.3302 -0.4318)
							(mid -0.402042 -0.402042)
							(end -0.4318 -0.3302)
						)
						(arc
							(start -0.4318 0.3302)
							(mid -0.402042 0.402042)
							(end -0.3302 0.4318)
						)
						(arc
							(start 0.3302 0.4318)
							(mid 0.402042 0.402042)
							(end 0.4318 0.3302)
						)
						(arc
							(start 0.4318 -0.3302)
							(mid 0.402042 -0.402042)
							(end 0.3302 -0.4318)
						)
					)
					(width 0)
					(fill yes)
				)
			)
		)
		(pad "2" smd custom
			(at 0 0.762 90)
			(size 0.2159 0.2159)
			(layers "F.Cu" "F.Mask" "F.Paste")
			(net "GND")
			(options
				(clearance outline)
				(anchor circle)
			)
			(primitives
				(gr_poly
					(pts
						(arc
							(start -0.3302 -0.4318)
							(mid -0.402042 -0.402042)
							(end -0.4318 -0.3302)
						)
						(arc
							(start -0.4318 0.3302)
							(mid -0.402042 0.402042)
							(end -0.3302 0.4318)
						)
						(arc
							(start 0.3302 0.4318)
							(mid 0.402042 0.402042)
							(end 0.4318 0.3302)
						)
						(arc
							(start 0.4318 -0.3302)
							(mid 0.402042 -0.402042)
							(end 0.3302 -0.4318)
						)
					)
					(width 0)
					(fill yes)
				)
			)
		)
	)
)
